#ISCELL
  mstr_misc dns *
  *
#ISCELL
  pure_quanta quanta_title_block_c *
  *
#ISCELL
  pure_quanta_power cad_note *
  *
#ISCELL
  pure_quanta_power universal_gnd *
  page263_i114
#CELL
  pure_quanta q_cap *
  page263_i115
#ISCELL
  standard offpage *
  page263_i116
#ISCELL
  standard offpage *
  page263_i117
#ISCELL
  pure_quanta_power universal_gnd *
  page263_i118
#CELL
  pure_quanta q_res *
  page263_i119
#CELL
  pure_quanta q_res *
  page263_i12
#ISCELL
  standard offpage *
  page263_i120
#ISCELL
  standard offpage *
  page263_i121
#ISCELL
  standard offpage *
  page263_i122
#ISCELL
  standard offpage *
  page263_i123
#ISCELL
  standard offpage *
  page263_i124
#ISCELL
  standard offpage *
  page263_i125
#ISCELL
  standard offpage *
  page263_i126
#ISCELL
  standard offpage *
  page263_i127
#ISCELL
  standard offpage *
  page263_i128
#ISCELL
  standard offpage *
  page263_i129
#CELL
  pure_quanta q_res *
  page263_i13
#CELL
  pure_quanta q_cap *
  page263_i130
#CELL
  pure_quanta q_res *
  page263_i131
#ISCELL
  standard offpage *
  page263_i132
#ISCELL
  standard offpage *
  page263_i133
#ISCELL
  standard offpage *
  page263_i134
#ISCELL
  standard offpage *
  page263_i135
#ISCELL
  standard offpage *
  page263_i136
#ISCELL
  standard offpage *
  page263_i137
#CELL
  pure_quanta q_res *
  page263_i138
#CELL
  pure_quanta q_res *
  page263_i139
#ISCELL
  pure_quanta_power universal_power *
  page263_i14
#CELL
  pure_quanta q_res *
  page263_i140
#CELL
  pure_quanta q_res *
  page263_i141
#CELL
  pure_quanta adc128d818cimtxnopb *
  page263_i142
#ISCELL
  pure_quanta_power universal_gnd *
  page263_i143
#ISCELL
  standard offpage *
  page263_i144
#ISCELL
  standard offpage *
  page263_i145
#ISCELL
  standard offpage *
  page263_i146
#ISCELL
  standard offpage *
  page263_i147
#ISCELL
  standard offpage *
  page263_i148
#ISCELL
  standard offpage *
  page263_i149
#CELL
  pure_quanta q_res *
  page263_i15
#ISCELL
  standard offpage *
  page263_i150
#ISCELL
  standard offpage *
  page263_i151
#CELL
  pure_quanta q_cap *
  page263_i152
#ISCELL
  pure_quanta_power universal_gnd *
  page263_i153
#CELL
  pure_quanta q_res *
  page263_i154
#ISCELL
  pure_quanta_power universal_gnd *
  page263_i155
#CELL
  pure_quanta max11617eeet *
  page263_i156
#ISCELL
  pure_quanta_power universal_gnd *
  page263_i157
#ISCELL
  standard offpage *
  page263_i158
#ISCELL
  standard offpage *
  page263_i159
#CELL
  pure_quanta q_res *
  page263_i16
#ISCELL
  standard offpage *
  page263_i160
#ISCELL
  standard offpage *
  page263_i161
#ISCELL
  standard offpage *
  page263_i162
#ISCELL
  standard offpage *
  page263_i163
#ISCELL
  pure_quanta_power universal_gnd *
  page263_i164
#CELL
  pure_quanta q_cap *
  page263_i165
#CELL
  pure_quanta q_cap *
  page263_i166
#ISCELL
  pure_quanta_power universal_gnd *
  page263_i167
#CELL
  pure_quanta q_inductor *
  page263_i168
#ISCELL
  pure_quanta_power universal_power *
  page263_i169
#ISCELL
  pure_quanta_power universal_power *
  page263_i170
#ISCELL
  standard offpage *
  page263_i171
#ISCELL
  standard offpage *
  page263_i172
#CELL
  pure_quanta q_cap *
  page263_i173
#ISCELL
  pure_quanta_power universal_gnd *
  page263_i174
#CELL
  pure_quanta q_cap *
  page263_i175
#ISCELL
  pure_quanta_power universal_gnd *
  page263_i176
#CELL
  pure_quanta q_res *
  page263_i177
#CELL
  pure_quanta q_res *
  page263_i178
#CELL
  pure_quanta q_res *
  page263_i179
#ISCELL
  pure_quanta_power universal_gnd *
  page263_i18
#ISCELL
  pure_quanta_power universal_gnd *
  page263_i181
#ISCELL
  standard offpage *
  page263_i182
#ISCELL
  pure_quanta_power universal_power *
  page263_i183
#ISCELL
  standard offpage *
  page263_i184
#CELL
  pure_quanta q_cap *
  page263_i185
#ISCELL
  pure_quanta_power universal_gnd *
  page263_i186
#CELL
  pure_quanta q_cap *
  page263_i187
#ISCELL
  pure_quanta_power universal_gnd *
  page263_i188
#CELL
  pure_quanta q_res *
  page263_i189
#CELL
  pure_quanta q_res *
  page263_i19
#CELL
  pure_quanta q_res *
  page263_i190
#CELL
  pure_quanta q_res *
  page263_i191
#ISCELL
  pure_quanta_power universal_gnd *
  page263_i193
#CELL
  pure_quanta q_res *
  page263_i194
#ISCELL
  pure_quanta_power universal_power *
  page263_i195
#ISCELL
  standard offpage *
  page263_i196
#ISCELL
  standard offpage *
  page263_i197
#CELL
  pure_quanta q_cap *
  page263_i198
#ISCELL
  pure_quanta_power universal_gnd *
  page263_i199
#ISCELL
  pure_quanta_power universal_power *
  page263_i20
#CELL
  pure_quanta q_cap *
  page263_i200
#ISCELL
  pure_quanta_power universal_gnd *
  page263_i201
#CELL
  pure_quanta q_res *
  page263_i202
#CELL
  pure_quanta q_res *
  page263_i203
#ISCELL
  pure_quanta_power universal_gnd *
  page263_i205
#ISCELL
  standard offpage *
  page263_i206
#ISCELL
  pure_quanta_power universal_power *
  page263_i207
#ISCELL
  standard offpage *
  page263_i208
#CELL
  pure_quanta q_cap *
  page263_i209
#CELL
  pure_quanta q_res *
  page263_i21
#ISCELL
  pure_quanta_power universal_gnd *
  page263_i210
#CELL
  pure_quanta q_cap *
  page263_i211
#ISCELL
  pure_quanta_power universal_gnd *
  page263_i212
#CELL
  pure_quanta q_res *
  page263_i213
#CELL
  pure_quanta q_res *
  page263_i214
#CELL
  pure_quanta q_res *
  page263_i215
#CELL
  pure_quanta q_res *
  page263_i216
#ISCELL
  pure_quanta_power universal_gnd *
  page263_i217
#ISCELL
  pure_quanta_power universal_power *
  page263_i218
#ISCELL
  standard offpage *
  page263_i219
#CELL
  pure_quanta q_res *
  page263_i22
#ISCELL
  standard offpage *
  page263_i220
#CELL
  pure_quanta q_cap *
  page263_i221
#ISCELL
  pure_quanta_power universal_gnd *
  page263_i222
#CELL
  pure_quanta q_cap *
  page263_i223
#ISCELL
  pure_quanta_power universal_gnd *
  page263_i224
#CELL
  pure_quanta q_res *
  page263_i225
#CELL
  pure_quanta q_res *
  page263_i226
#CELL
  pure_quanta q_res *
  page263_i227
#ISCELL
  pure_quanta_power universal_gnd *
  page263_i229
#CELL
  pure_quanta q_res *
  page263_i230
#CELL
  pure_quanta q_res *
  page263_i231
#CELL
  pure_quanta q_cap *
  page263_i232
#ISCELL
  pure_quanta_power universal_power *
  page263_i233
#ISCELL
  standard offpage *
  page263_i234
#ISCELL
  standard offpage *
  page263_i235
#ISCELL
  pure_quanta_power universal_gnd *
  page263_i236
#CELL
  pure_quanta q_cap *
  page263_i237
#ISCELL
  pure_quanta_power universal_gnd *
  page263_i238
#CELL
  pure_quanta q_res *
  page263_i239
#ISCELL
  pure_quanta_power universal_gnd *
  page263_i241
#CELL
  pure_quanta q_res *
  page263_i242
#CELL
  pure_quanta q_res *
  page263_i243
#CELL
  pure_quanta q_res *
  page263_i244
#CELL
  pure_quanta q_res *
  page263_i245
#CELL
  pure_quanta q_res *
  page263_i246
#CELL
  pure_quanta q_res *
  page263_i247
#ISCELL
  pure_quanta_power universal_gnd *
  page263_i42
#CELL
  pure_quanta q_cap *
  page263_i43
#ISCELL
  pure_quanta_power universal_gnd *
  page263_i44
#CELL
  pure_quanta q_cap *
  page263_i45
#ISCELL
  pure_quanta_power universal_gnd *
  page263_i46
#ISCELL
  standard offpage *
  page263_i47
#ISCELL
  standard offpage *
  page263_i48
#ISCELL
  pure_quanta_power universal_gnd *
  page263_i49
#ISCELL
  pure_quanta_power universal_gnd *
  page263_i55
#ISCELL
  pure_quanta_power universal_gnd *
  page263_i56
#CELL
  pure_quanta q_res *
  page263_i57
#CELL
  pure_quanta q_res *
  page263_i58
#CELL
  pure_quanta q_res *
  page263_i59
#CELL
  pure_quanta q_res *
  page263_i60
#ISCELL
  pure_quanta_power universal_power *
  page263_i61
#ISCELL
  pure_quanta_power universal_power *
  page263_i66
#ISCELL
  pure_quanta_power universal_gnd *
  page263_i67
#CELL
  pure_quanta q_cap *
  page263_i68
#CELL
  pure_quanta q_inductor *
  page263_i69
#CELL
  pure_quanta q_cap *
  page263_i76
#CELL
  pure_quanta q_cap *
  page263_i77
#ISCELL
  standard offpage *
  page263_i78
#ISCELL
  standard offpage *
  page263_i79
#ISCELL
  pure_quanta_power universal_gnd *
  page263_i9
